(kicad_pcb
	(version 20260206)
	(generator "pcbnew")
	(generator_version "10.0")
	(general
		(thickness 1.6)
		(legacy_teardrops no)
	)
	(paper "A4")
	(title_block
		(title "Wiwynn_Tioga_Pass_MB.brd")
		(comment 1 "Tioga Pass / footprint 2254 of 4770 (U5D1), pads 2627-2736 of 3647")
	)
	(layers
		(0 "F.Cu" signal "TOP")
		(4 "In1.Cu" signal "L2GND")
		(6 "In2.Cu" signal "L3")
		(8 "In3.Cu" signal "L4GND")
		(10 "In4.Cu" signal "L5")
		(12 "In5.Cu" signal "L6GND")
		(14 "In6.Cu" signal "L7VCC")
		(16 "In7.Cu" signal "L8VCC")
		(18 "In8.Cu" signal "L9GND")
		(20 "In9.Cu" signal "L10")
		(22 "In10.Cu" signal "L11GND")
		(24 "In11.Cu" signal "L12")
		(26 "In12.Cu" signal "L13GND")
		(2 "B.Cu" signal "BOTTOM")
		(9 "F.Adhes" user "F.Adhesive")
		(11 "B.Adhes" user "B.Adhesive")
		(13 "F.Paste" user "Package Geometry/Pastemask Top")
		(15 "B.Paste" user "Package Geometry/Pastemask Bottom")
		(5 "F.SilkS" user "Ref Des/Silkscreen Top")
		(7 "B.SilkS" user "Ref Des/Silkscreen Bottom")
		(1 "F.Mask" user "Board Geometry/Soldermask Top")
		(3 "B.Mask" user "Board Geometry/Soldermask Bottom")
		(17 "Dwgs.User" user "User.Drawings")
		(19 "Cmts.User" user "User.Comments")
		(21 "Eco1.User" user "User.Eco1")
		(23 "Eco2.User" user "User.Eco2")
		(25 "Edge.Cuts" user "Board Geometry/Outline")
		(27 "Margin" user)
		(31 "F.CrtYd" user "Package Geometry/Place Bound Top")
		(29 "B.CrtYd" user "Package Geometry/Place Bound Bottom")
		(35 "F.Fab" user "Ref Des/Assembly Top")
		(33 "B.Fab" user "Ref Des/Assembly Bottom")
	)
	(footprint ""
		(layer "F.Cu")
		(at 270.000222 -76.550012 180)
		(property "Reference" "U5D1"
			(at 19.124422 31.601918 0)
			(unlocked yes)
			(layer "F.SilkS")
			(effects
				(font
					(size 0.7874 0.5842)
					(thickness 0.1524)
				)
			)
		)
		(property "Value" ""
			(at 0 0 180)
			(layer "F.Fab")
			(effects
				(font
					(size 1.27 1.27)
				)
			)
		)
		(duplicate_pad_numbers_are_jumpers no)
		(pad "DU40" smd circle
			(at -3.769106 22.445726)
			(size 0.4318 0.4318)
			(layers "F.Cu" "F.Mask" "F.Paste")
			(net "M_E_DQ<39>")
		)
		(pad "DU42" smd circle
			(at -2.052066 22.445726)
			(size 0.4318 0.4318)
			(layers "F.Cu" "F.Mask" "F.Paste")
			(net "M_E_DQ<32>")
		)
		(pad "DU44" smd circle
			(at 1.193546 20.645628)
			(size 0.508 0.508)
			(layers "F.Cu" "F.Mask" "F.Paste")
			(net "TP_CPU0_RSVD_26")
		)
		(pad "DU46" smd circle
			(at 2.910586 20.645628)
			(size 0.4318 0.4318)
			(layers "F.Cu" "F.Mask" "F.Paste")
			(net "PVDDQ_DEF")
		)
		(pad "DU48" smd circle
			(at 4.627626 20.645628)
			(size 0.4318 0.4318)
			(layers "F.Cu" "F.Mask" "F.Paste")
			(net "PVDDQ_DEF")
		)
		(pad "DU50" smd circle
			(at 6.344412 20.645628)
			(size 0.4318 0.4318)
			(layers "F.Cu" "F.Mask" "F.Paste")
			(net "PVDDQ_DEF")
		)
		(pad "DU52" smd circle
			(at 8.061452 20.645628)
			(size 0.4318 0.4318)
			(layers "F.Cu" "F.Mask" "F.Paste")
			(net "PVDDQ_DEF")
		)
		(pad "DU54" smd circle
			(at 9.778492 20.645628)
			(size 0.4318 0.4318)
			(layers "F.Cu" "F.Mask" "F.Paste")
			(net "PVDDQ_DEF")
		)
		(pad "DU56" smd circle
			(at 11.495532 20.645628)
			(size 0.4318 0.4318)
			(layers "F.Cu" "F.Mask" "F.Paste")
			(net "PVDDQ_DEF")
		)
		(pad "DU58" smd circle
			(at 13.212572 20.645628)
			(size 0.4318 0.4318)
			(layers "F.Cu" "F.Mask" "F.Paste")
			(net "PVDDQ_DEF")
		)
		(pad "DU60" smd circle
			(at 14.929612 20.645628)
			(size 0.4318 0.4318)
			(layers "F.Cu" "F.Mask" "F.Paste")
			(net "PVDDQ_DEF")
		)
		(pad "DU62" smd circle
			(at 16.646398 20.645628)
			(size 0.4318 0.4318)
			(layers "F.Cu" "F.Mask" "F.Paste")
			(net "PVDDQ_DEF")
		)
		(pad "DU64" smd circle
			(at 18.363438 20.645628)
			(size 0.4318 0.4318)
			(layers "F.Cu" "F.Mask" "F.Paste")
			(net "PVDDQ_DEF")
		)
		(pad "DU66" smd circle
			(at 20.080478 20.645628)
			(size 0.4318 0.4318)
			(layers "F.Cu" "F.Mask" "F.Paste")
			(net "M_E_ECC<6>")
		)
		(pad "DU68" smd circle
			(at 21.797518 20.645628)
			(size 0.4318 0.4318)
			(layers "F.Cu" "F.Mask" "F.Paste")
			(net "M_E_ECC<4>")
		)
		(pad "DU70" smd circle
			(at 23.514558 20.645628)
			(size 0.4318 0.4318)
			(layers "F.Cu" "F.Mask" "F.Paste")
			(net "GND")
		)
		(pad "DU72" smd circle
			(at 25.231598 20.645628)
			(size 0.4318 0.4318)
			(layers "F.Cu" "F.Mask" "F.Paste")
			(net "GND")
		)
		(pad "DU74" smd circle
			(at 26.948384 20.645628)
			(size 0.4318 0.4318)
			(layers "F.Cu" "F.Mask" "F.Paste")
			(net "M_D_DQ<31>")
		)
		(pad "DU76" smd circle
			(at 28.665424 20.645628)
			(size 0.4318 0.4318)
			(layers "F.Cu" "F.Mask" "F.Paste")
			(net "M_D_DQ<25>")
		)
		(pad "DU78" smd circle
			(at 30.382464 20.645628)
			(size 0.4318 0.4318)
			(layers "F.Cu" "F.Mask" "F.Paste")
			(net "GND")
		)
		(pad "DU80" smd circle
			(at 32.099504 20.645628)
			(size 0.4318 0.4318)
			(layers "F.Cu" "F.Mask" "F.Paste")
			(net "GND")
		)
		(pad "DU82" smd circle
			(at 33.816544 20.645628)
			(size 0.4318 0.4318)
			(layers "F.Cu" "F.Mask" "F.Paste")
			(net "GND")
		)
		(pad "DU84" smd circle
			(at 35.533584 20.645628)
			(size 0.4318 0.4318)
			(layers "F.Cu" "F.Mask" "F.Paste")
			(net "GND")
		)
		(pad "DV3" smd circle
			(at -35.533584 22.940772)
			(size 0.4318 0.4318)
			(layers "F.Cu" "F.Mask" "F.Paste")
			(net "P3E_CPU0_PE1_PCH_TXN<9>")
		)
		(pad "DV5" smd circle
			(at -33.816544 22.940772)
			(size 0.4318 0.4318)
			(layers "F.Cu" "F.Mask" "F.Paste")
			(net "P3E_CPU0_PE1_PCH_TXP<11>")
		)
		(pad "DV7" smd circle
			(at -32.099504 22.940772)
			(size 0.4318 0.4318)
			(layers "F.Cu" "F.Mask" "F.Paste")
			(net "P3E_CPU0_PE1_PCH_TXN<12>")
		)
		(pad "DV9" smd circle
			(at -30.382464 22.940772)
			(size 0.4318 0.4318)
			(layers "F.Cu" "F.Mask" "F.Paste")
			(net "P3E_CPU0_PE3_OCP_TXP<5>")
		)
		(pad "DV11" smd circle
			(at -28.665424 22.940772)
			(size 0.4318 0.4318)
			(layers "F.Cu" "F.Mask" "F.Paste")
			(net "PVCCIO_CPU0")
		)
		(pad "DV13" smd circle
			(at -26.948384 22.940772)
			(size 0.4318 0.4318)
			(layers "F.Cu" "F.Mask" "F.Paste")
			(net "P3E_CPU0_PE1_PCH_RXN<12>")
		)
		(pad "DV15" smd circle
			(at -25.231598 22.940772)
			(size 0.4318 0.4318)
			(layers "F.Cu" "F.Mask" "F.Paste")
			(net "P3E_CPU0_PE1_PCH_RXP<14>")
		)
		(pad "DV17" smd circle
			(at -23.514558 22.940772)
			(size 0.4318 0.4318)
			(layers "F.Cu" "F.Mask" "F.Paste")
			(net "P3E_CPU0_PE3_OCP_RXP<2>")
		)
		(pad "DV19" smd circle
			(at -21.797518 22.940772)
			(size 0.4318 0.4318)
			(layers "F.Cu" "F.Mask" "F.Paste")
			(net "GND")
		)
		(pad "DV21" smd circle
			(at -20.080478 22.940772)
			(size 0.4318 0.4318)
			(layers "F.Cu" "F.Mask" "F.Paste")
			(net "GND")
		)
		(pad "DV23" smd circle
			(at -18.363438 22.940772)
			(size 0.4318 0.4318)
			(layers "F.Cu" "F.Mask" "F.Paste")
			(net "M_D_DQS_DN<7>")
		)
		(pad "DV25" smd circle
			(at -16.646398 22.940772)
			(size 0.4318 0.4318)
			(layers "F.Cu" "F.Mask" "F.Paste")
			(net "GND")
		)
		(pad "DV27" smd circle
			(at -14.929612 22.940772)
			(size 0.4318 0.4318)
			(layers "F.Cu" "F.Mask" "F.Paste")
			(net "GND")
		)
		(pad "DV29" smd circle
			(at -13.212572 22.940772)
			(size 0.4318 0.4318)
			(layers "F.Cu" "F.Mask" "F.Paste")
			(net "M_D_DQS_DN<6>")
		)
		(pad "DV31" smd circle
			(at -11.495532 22.940772)
			(size 0.4318 0.4318)
			(layers "F.Cu" "F.Mask" "F.Paste")
			(net "GND")
		)
		(pad "DV33" smd circle
			(at -9.778492 22.940772)
			(size 0.4318 0.4318)
			(layers "F.Cu" "F.Mask" "F.Paste")
			(net "GND")
		)
		(pad "DV35" smd circle
			(at -8.061452 22.940772)
			(size 0.4318 0.4318)
			(layers "F.Cu" "F.Mask" "F.Paste")
			(net "M_D_DQS_DN<5>")
		)
		(pad "DV37" smd circle
			(at -6.344412 22.940772)
			(size 0.4318 0.4318)
			(layers "F.Cu" "F.Mask" "F.Paste")
			(net "GND")
		)
		(pad "DV39" smd circle
			(at -4.627626 22.940772)
			(size 0.4318 0.4318)
			(layers "F.Cu" "F.Mask" "F.Paste")
			(net "GND")
		)
		(pad "DV41" smd circle
			(at -2.910586 22.940772)
			(size 0.4318 0.4318)
			(layers "F.Cu" "F.Mask" "F.Paste")
			(net "M_E_DQS_DN<4>")
		)
		(pad "DV45" smd circle
			(at 2.052066 21.140674)
			(size 0.4318 0.4318)
			(layers "F.Cu" "F.Mask" "F.Paste")
			(net "M_D_CS_N<6>")
		)
		(pad "DV47" smd circle
			(at 3.769106 21.140674)
			(size 0.4318 0.4318)
			(layers "F.Cu" "F.Mask" "F.Paste")
			(net "M_D_C<2>")
		)
		(pad "DV49" smd circle
			(at 5.485892 21.140674)
			(size 0.4318 0.4318)
			(layers "F.Cu" "F.Mask" "F.Paste")
			(net "M_D_MA<15>")
		)
		(pad "DV51" smd circle
			(at 7.202932 21.140674)
			(size 0.4318 0.4318)
			(layers "F.Cu" "F.Mask" "F.Paste")
			(net "M_E_CS_N<0>")
		)
		(pad "DV53" smd circle
			(at 8.919972 21.140674)
			(size 0.4318 0.4318)
			(layers "F.Cu" "F.Mask" "F.Paste")
			(net "M_E_PAR")
		)
		(pad "DV55" smd circle
			(at 10.637012 21.140674)
			(size 0.4318 0.4318)
			(layers "F.Cu" "F.Mask" "F.Paste")
			(net "M_E_BA<1>")
		)
		(pad "DV57" smd circle
			(at 12.354052 21.140674)
			(size 0.4318 0.4318)
			(layers "F.Cu" "F.Mask" "F.Paste")
			(net "M_E_MA<2>")
		)
		(pad "DV59" smd circle
			(at 14.071092 21.140674)
			(size 0.4318 0.4318)
			(layers "F.Cu" "F.Mask" "F.Paste")
			(net "M_E_MA<9>")
		)
		(pad "DV61" smd circle
			(at 15.787878 21.140674)
			(size 0.4318 0.4318)
			(layers "F.Cu" "F.Mask" "F.Paste")
			(net "TP_CPU0_RSVD_25")
		)
		(pad "DV63" smd circle
			(at 17.504918 21.140674)
			(size 0.4318 0.4318)
			(layers "F.Cu" "F.Mask" "F.Paste")
			(net "M_DEF_RST_N")
		)
		(pad "DV65" smd circle
			(at 19.221958 21.140674)
			(size 0.4318 0.4318)
			(layers "F.Cu" "F.Mask" "F.Paste")
			(net "M_E_ECC<2>")
		)
		(pad "DV67" smd circle
			(at 20.938998 21.140674)
			(size 0.4318 0.4318)
			(layers "F.Cu" "F.Mask" "F.Paste")
			(net "M_E_DQS_DN<17>")
		)
		(pad "DV69" smd circle
			(at 22.656038 21.140674)
			(size 0.4318 0.4318)
			(layers "F.Cu" "F.Mask" "F.Paste")
			(net "M_E_ECC<5>")
		)
		(pad "DV71" smd circle
			(at 24.373078 21.140674)
			(size 0.4318 0.4318)
			(layers "F.Cu" "F.Mask" "F.Paste")
			(net "TP_CPU0_RSVD_24")
		)
		(pad "DV73" smd circle
			(at 26.090118 21.140674)
			(size 0.4318 0.4318)
			(layers "F.Cu" "F.Mask" "F.Paste")
			(net "GND")
		)
		(pad "DV75" smd circle
			(at 27.806904 21.140674)
			(size 0.4318 0.4318)
			(layers "F.Cu" "F.Mask" "F.Paste")
			(net "M_D_DQS_DN<3>")
		)
		(pad "DV77" smd circle
			(at 29.523944 21.140674)
			(size 0.4318 0.4318)
			(layers "F.Cu" "F.Mask" "F.Paste")
			(net "GND")
		)
		(pad "DV79" smd circle
			(at 31.240984 21.140674)
			(size 0.4318 0.4318)
			(layers "F.Cu" "F.Mask" "F.Paste")
			(net "M_E_DQS_DP<11>")
		)
		(pad "DV81" smd circle
			(at 32.958024 21.140674)
			(size 0.4318 0.4318)
			(layers "F.Cu" "F.Mask" "F.Paste")
			(net "GND")
		)
		(pad "DV83" smd circle
			(at 34.675064 21.140674)
			(size 0.4318 0.4318)
			(layers "F.Cu" "F.Mask" "F.Paste")
			(net "M_D_DQ<10>")
		)
		(pad "DV85" smd custom
			(at 36.392104 21.140674 270)
			(size 0.10795 0.10795)
			(layers "F.Cu" "F.Mask" "F.Paste")
			(net "M_D_DQ<15>")
			(options
				(clearance outline)
				(anchor circle)
			)
			(primitives
				(gr_poly
					(pts
						(arc
							(start 0.2159 -0.0381)
							(mid 0 -0.254)
							(end -0.2159 -0.0381)
						)
						(arc
							(start -0.2159 0.0381)
							(mid 0 0.254)
							(end 0.2159 0.0381)
						)
					)
					(width 0)
					(fill yes)
				)
			)
		)
		(pad "DW2" smd custom
			(at -36.392104 23.436326 90)
			(size 0.10795 0.10795)
			(layers "F.Cu" "F.Mask" "F.Paste")
			(net "GND")
			(options
				(clearance outline)
				(anchor circle)
			)
			(primitives
				(gr_poly
					(pts
						(arc
							(start 0.2159 -0.0381)
							(mid 0 -0.254)
							(end -0.2159 -0.0381)
						)
						(arc
							(start -0.2159 0.0381)
							(mid 0 0.254)
							(end 0.2159 0.0381)
						)
					)
					(width 0)
					(fill yes)
				)
			)
		)
		(pad "DW4" smd circle
			(at -34.675064 23.436326)
			(size 0.4318 0.4318)
			(layers "F.Cu" "F.Mask" "F.Paste")
			(net "P3E_CPU0_PE1_PCH_TXN<10>")
		)
		(pad "DW6" smd circle
			(at -32.958024 23.436326)
			(size 0.4318 0.4318)
			(layers "F.Cu" "F.Mask" "F.Paste")
			(net "P3E_CPU0_PE1_PCH_TXP<13>")
		)
		(pad "DW8" smd circle
			(at -31.240984 23.436326)
			(size 0.4318 0.4318)
			(layers "F.Cu" "F.Mask" "F.Paste")
			(net "GND")
		)
		(pad "DW10" smd circle
			(at -29.523944 23.436326)
			(size 0.4318 0.4318)
			(layers "F.Cu" "F.Mask" "F.Paste")
			(net "P3E_CPU0_PE3_OCP_TXN<5>")
		)
		(pad "DW12" smd circle
			(at -27.806904 23.436326)
			(size 0.4318 0.4318)
			(layers "F.Cu" "F.Mask" "F.Paste")
			(net "GND")
		)
		(pad "DW14" smd circle
			(at -26.090118 23.436326)
			(size 0.4318 0.4318)
			(layers "F.Cu" "F.Mask" "F.Paste")
			(net "P3E_CPU0_PE1_PCH_RXN<13>")
		)
		(pad "DW16" smd circle
			(at -24.373078 23.436326)
			(size 0.4318 0.4318)
			(layers "F.Cu" "F.Mask" "F.Paste")
			(net "P3E_CPU0_PE3_OCP_RXN<2>")
		)
		(pad "DW18" smd circle
			(at -22.656038 23.436326)
			(size 0.4318 0.4318)
			(layers "F.Cu" "F.Mask" "F.Paste")
			(net "P3E_CPU0_PE3_OCP_RXN<1>")
		)
		(pad "DW20" smd circle
			(at -20.938998 23.436326)
			(size 0.4318 0.4318)
			(layers "F.Cu" "F.Mask" "F.Paste")
			(net "GND")
		)
		(pad "DW22" smd circle
			(at -19.221958 23.436326)
			(size 0.4318 0.4318)
			(layers "F.Cu" "F.Mask" "F.Paste")
			(net "M_D_DQ<63>")
		)
		(pad "DW24" smd circle
			(at -17.504918 23.436326)
			(size 0.4318 0.4318)
			(layers "F.Cu" "F.Mask" "F.Paste")
			(net "GND")
		)
		(pad "DW26" smd circle
			(at -15.787878 23.436326)
			(size 0.4318 0.4318)
			(layers "F.Cu" "F.Mask" "F.Paste")
			(net "M_E_DQS_DP<15>")
		)
		(pad "DW28" smd circle
			(at -14.071092 23.436326)
			(size 0.4318 0.4318)
			(layers "F.Cu" "F.Mask" "F.Paste")
			(net "GND")
		)
		(pad "DW30" smd circle
			(at -12.354052 23.436326)
			(size 0.4318 0.4318)
			(layers "F.Cu" "F.Mask" "F.Paste")
			(net "GND")
		)
		(pad "DW32" smd circle
			(at -10.637012 23.436326)
			(size 0.4318 0.4318)
			(layers "F.Cu" "F.Mask" "F.Paste")
			(net "M_E_DQS_DP<14>")
		)
		(pad "DW34" smd circle
			(at -8.919972 23.436326)
			(size 0.4318 0.4318)
			(layers "F.Cu" "F.Mask" "F.Paste")
			(net "GND")
		)
		(pad "DW36" smd circle
			(at -7.202932 23.436326)
			(size 0.4318 0.4318)
			(layers "F.Cu" "F.Mask" "F.Paste")
			(net "GND")
		)
		(pad "DW38" smd circle
			(at -5.485892 23.436326)
			(size 0.4318 0.4318)
			(layers "F.Cu" "F.Mask" "F.Paste")
			(net "M_D_DQS_DP<13>")
		)
		(pad "DW40" smd circle
			(at -3.769106 23.436326)
			(size 0.4318 0.4318)
			(layers "F.Cu" "F.Mask" "F.Paste")
			(net "GND")
		)
		(pad "DW42" smd circle
			(at -2.052066 23.436326)
			(size 0.4318 0.4318)
			(layers "F.Cu" "F.Mask" "F.Paste")
			(net "M_E_DQ<33>")
		)
		(pad "DW44" smd circle
			(at 1.193546 21.636228)
			(size 0.508 0.508)
			(layers "F.Cu" "F.Mask" "F.Paste")
			(net "TP_CPU0_RSVD_23")
		)
		(pad "DW46" smd circle
			(at 2.910586 21.636228)
			(size 0.4318 0.4318)
			(layers "F.Cu" "F.Mask" "F.Paste")
			(net "TP_CPU0_RSVD_22")
		)
		(pad "DW48" smd circle
			(at 4.627626 21.636228)
			(size 0.4318 0.4318)
			(layers "F.Cu" "F.Mask" "F.Paste")
			(net "M_D_MA<13>")
		)
		(pad "DW50" smd circle
			(at 6.344412 21.636228)
			(size 0.4318 0.4318)
			(layers "F.Cu" "F.Mask" "F.Paste")
			(net "M_E_CS_N<4>")
		)
		(pad "DW52" smd circle
			(at 8.061452 21.636228)
			(size 0.4318 0.4318)
			(layers "F.Cu" "F.Mask" "F.Paste")
			(net "M_E_MA<0>")
		)
		(pad "DW54" smd circle
			(at 9.778492 21.636228)
			(size 0.4318 0.4318)
			(layers "F.Cu" "F.Mask" "F.Paste")
			(net "M_D_MA<10>")
		)
		(pad "DW56" smd circle
			(at 11.495532 21.636228)
			(size 0.4318 0.4318)
			(layers "F.Cu" "F.Mask" "F.Paste")
			(net "M_D_CLK_DN<2>")
		)
		(pad "DW58" smd circle
			(at 13.212572 21.636228)
			(size 0.4318 0.4318)
			(layers "F.Cu" "F.Mask" "F.Paste")
			(net "M_E_MA<1>")
		)
		(pad "DW60" smd circle
			(at 14.929612 21.636228)
			(size 0.4318 0.4318)
			(layers "F.Cu" "F.Mask" "F.Paste")
			(net "M_D_ACT_N")
		)
		(pad "DW62" smd circle
			(at 16.646398 21.636228)
			(size 0.4318 0.4318)
			(layers "F.Cu" "F.Mask" "F.Paste")
			(net "M_D_BG<1>")
		)
		(pad "DW64" smd circle
			(at 18.363438 21.636228)
			(size 0.4318 0.4318)
			(layers "F.Cu" "F.Mask" "F.Paste")
			(net "GND")
		)
		(pad "DW66" smd circle
			(at 20.080478 21.636228)
			(size 0.4318 0.4318)
			(layers "F.Cu" "F.Mask" "F.Paste")
			(net "GND")
		)
		(pad "DW68" smd circle
			(at 21.797518 21.636228)
			(size 0.4318 0.4318)
			(layers "F.Cu" "F.Mask" "F.Paste")
			(net "GND")
		)
		(pad "DW70" smd circle
			(at 23.514558 21.636228)
			(size 0.4318 0.4318)
			(layers "F.Cu" "F.Mask" "F.Paste")
			(net "GND")
		)
		(pad "DW72" smd circle
			(at 25.231598 21.636228)
			(size 0.4318 0.4318)
			(layers "F.Cu" "F.Mask" "F.Paste")
			(net "GND")
		)
		(pad "DW74" smd circle
			(at 26.948384 21.636228)
			(size 0.4318 0.4318)
			(layers "F.Cu" "F.Mask" "F.Paste")
			(net "GND")
		)
		(pad "DW76" smd circle
			(at 28.665424 21.636228)
			(size 0.4318 0.4318)
			(layers "F.Cu" "F.Mask" "F.Paste")
			(net "GND")
		)
		(pad "DW78" smd circle
			(at 30.382464 21.636228)
			(size 0.4318 0.4318)
			(layers "F.Cu" "F.Mask" "F.Paste")
			(net "M_E_DQ<22>")
		)
		(pad "DW80" smd circle
			(at 32.099504 21.636228)
			(size 0.4318 0.4318)
			(layers "F.Cu" "F.Mask" "F.Paste")
			(net "M_E_DQ<16>")
		)
		(pad "DW82" smd circle
			(at 33.816544 21.636228)
			(size 0.4318 0.4318)
			(layers "F.Cu" "F.Mask" "F.Paste")
			(net "GND")
		)
		(pad "DW84" smd circle
			(at 35.533584 21.636228)
			(size 0.4318 0.4318)
			(layers "F.Cu" "F.Mask" "F.Paste")
			(net "GND")
		)
		(pad "DY3" smd custom
			(at -35.533584 23.931626 135)
			(size 0.10795 0.10795)
			(layers "F.Cu" "F.Mask" "F.Paste")
			(net "TP_CPU0_RSVD_21")
			(options
				(clearance outline)
				(anchor circle)
			)
			(primitives
				(gr_poly
					(pts
						(arc
							(start 0.2159 -0.0381)
							(mid 0 -0.254)
							(end -0.2159 -0.0381)
						)
						(arc
							(start -0.2159 0.0381)
							(mid 0 0.254)
							(end 0.2159 0.0381)
						)
					)
					(width 0)
					(fill yes)
				)
			)
		)
		(pad "DY5" smd circle
			(at -33.816544 23.931626)
			(size 0.4318 0.4318)
			(layers "F.Cu" "F.Mask" "F.Paste")
			(net "GND")
		)
		(pad "DY7" smd circle
			(at -32.099504 23.931626)
			(size 0.4318 0.4318)
			(layers "F.Cu" "F.Mask" "F.Paste")
			(net "P3E_CPU0_PE1_PCH_TXN<13>")
		)
		(pad "DY9" smd circle
			(at -30.382464 23.931626)
			(size 0.4318 0.4318)
			(layers "F.Cu" "F.Mask" "F.Paste")
			(net "P3E_CPU0_PE3_OCP_TXP<4>")
		)
	)
)
